(kicad_pcb
	(version 20260206)
	(generator "pcbnew")
	(generator_version "10.0")
	(general
		(thickness 1.6)
		(legacy_teardrops no)
	)
	(paper "A4")
	(title_block
		(title "Wiwynn_Tioga_Pass_MB.brd")
		(comment 1 "Tioga Pass / footprints 991-996 of 4770")
	)
	(layers
		(0 "F.Cu" signal "TOP")
		(4 "In1.Cu" signal "L2GND")
		(6 "In2.Cu" signal "L3")
		(8 "In3.Cu" signal "L4GND")
		(10 "In4.Cu" signal "L5")
		(12 "In5.Cu" signal "L6GND")
		(14 "In6.Cu" signal "L7VCC")
		(16 "In7.Cu" signal "L8VCC")
		(18 "In8.Cu" signal "L9GND")
		(20 "In9.Cu" signal "L10")
		(22 "In10.Cu" signal "L11GND")
		(24 "In11.Cu" signal "L12")
		(26 "In12.Cu" signal "L13GND")
		(2 "B.Cu" signal "BOTTOM")
		(9 "F.Adhes" user "F.Adhesive")
		(11 "B.Adhes" user "B.Adhesive")
		(13 "F.Paste" user "Package Geometry/Pastemask Top")
		(15 "B.Paste" user "Package Geometry/Pastemask Bottom")
		(5 "F.SilkS" user "Ref Des/Silkscreen Top")
		(7 "B.SilkS" user "Ref Des/Silkscreen Bottom")
		(1 "F.Mask" user "Board Geometry/Soldermask Top")
		(3 "B.Mask" user "Board Geometry/Soldermask Bottom")
		(17 "Dwgs.User" user "User.Drawings")
		(19 "Cmts.User" user "User.Comments")
		(21 "Eco1.User" user "User.Eco1")
		(23 "Eco2.User" user "User.Eco2")
		(25 "Edge.Cuts" user "Board Geometry/Outline")
		(27 "Margin" user)
		(31 "F.CrtYd" user "Package Geometry/Place Bound Top")
		(29 "B.CrtYd" user "Package Geometry/Place Bound Bottom")
		(35 "F.Fab" user "Ref Des/Assembly Top")
		(33 "B.Fab" user "Ref Des/Assembly Bottom")
	)
	(footprint ""
		(layer "F.Cu")
		(at 429.847248 -48.813466)
		(property "Reference" "Y9F2"
			(at 4.41071 2.95656 90)
			(unlocked yes)
			(layer "F.SilkS")
			(effects
				(font
					(size 0.7874 0.5842)
					(thickness 0.1524)
				)
				(justify left)
			)
		)
		(property "Value" ""
			(at 0 0 0)
			(layer "F.Fab")
			(effects
				(font
					(size 1.27 1.27)
				)
			)
		)
		(duplicate_pad_numbers_are_jumpers no)
		(fp_circle
			(center -1.088644 0.020066)
			(end -0.961644 0.020066)
			(stroke
				(width 0.254)
				(type default)
			)
			(fill no)
			(layer "F.SilkS")
		)
		(fp_rect
			(start -0.500126 2.750058)
			(end 2.100072 -0.54991)
			(stroke
				(width 0)
				(type default)
			)
			(fill no)
			(layer "F.CrtYd")
		)
		(fp_line
			(start -0.500126 -0.54991)
			(end 2.100072 -0.54991)
			(stroke
				(width 0.1)
				(type default)
			)
			(layer "F.Fab")
		)
		(fp_line
			(start -0.500126 2.750058)
			(end -0.500126 -0.54991)
			(stroke
				(width 0.1)
				(type default)
			)
			(layer "F.Fab")
		)
		(fp_line
			(start 2.100072 -0.54991)
			(end 2.100072 2.750058)
			(stroke
				(width 0.1)
				(type default)
			)
			(layer "F.Fab")
		)
		(fp_line
			(start 2.100072 2.750058)
			(end -0.500126 2.750058)
			(stroke
				(width 0.1)
				(type default)
			)
			(layer "F.Fab")
		)
		(fp_circle
			(center -1.218946 -0.125984)
			(end -1.091946 -0.125984)
			(stroke
				(width 0.254)
				(type default)
			)
			(fill no)
			(layer "F.Fab")
		)
		(pad "1" smd rect
			(at 0 0)
			(size 1.1938 1.397)
			(layers "F.Cu" "F.Mask" "F.Paste")
			(net "PU_24M_OSC_OE")
		)
		(pad "2" smd rect
			(at 0 2.199894)
			(size 1.1938 1.397)
			(layers "F.Cu" "F.Mask" "F.Paste")
			(net "GND")
		)
		(pad "3" smd rect
			(at 1.599946 2.199894)
			(size 1.1938 1.397)
			(layers "F.Cu" "F.Mask" "F.Paste")
			(net "CLK_24M_BMC_CLKIN_R")
		)
		(pad "4" smd rect
			(at 1.599946 0)
			(size 1.1938 1.397)
			(layers "F.Cu" "F.Mask" "F.Paste")
			(net "P3V3_STBY")
		)
	)
	(footprint ""
		(layer "F.Cu")
		(at 162.7886 -72.644 90)
		(property "Reference" "C3D22"
			(at 0 0 90)
			(layer "F.SilkS")
			(hide yes)
			(effects
				(font
					(size 1.27 1.27)
				)
			)
		)
		(property "Value" ""
			(at 0 0 90)
			(layer "F.Fab")
			(effects
				(font
					(size 1.27 1.27)
				)
			)
		)
		(duplicate_pad_numbers_are_jumpers no)
		(fp_poly
			(pts
				(xy -0.7239 -0.2159) (xy 0.7239 -0.2159) (xy 0.7239 1.9939) (xy -0.7239 1.9939)
			)
			(stroke
				(width 0)
				(type default)
			)
			(fill no)
			(layer "F.CrtYd")
		)
		(fp_line
			(start 0.7239 -0.2159)
			(end -0.7239 -0.2159)
			(stroke
				(width 0.1)
				(type default)
			)
			(layer "F.Fab")
		)
		(fp_line
			(start -0.7239 -0.2159)
			(end -0.7239 1.9939)
			(stroke
				(width 0.1)
				(type default)
			)
			(layer "F.Fab")
		)
		(fp_line
			(start 0.7239 1.9939)
			(end 0.7239 -0.2159)
			(stroke
				(width 0.1)
				(type default)
			)
			(layer "F.Fab")
		)
		(fp_line
			(start -0.7239 1.9939)
			(end 0.7239 1.9939)
			(stroke
				(width 0.1)
				(type default)
			)
			(layer "F.Fab")
		)
		(pad "1" smd rect
			(at 0 0 90)
			(size 1.27 1.016)
			(layers "F.Cu" "F.Mask" "F.Paste")
			(net "P3V3_DB1200")
		)
		(pad "2" smd rect
			(at 0 1.778 90)
			(size 1.27 1.016)
			(layers "F.Cu" "F.Mask" "F.Paste")
			(net "GND")
		)
		(zone
			(layer "F.Cu")
			(hatch none 0.5)
			(connect_pads
				(clearance 0)
			)
			(min_thickness 0.25)
			(keepout
				(tracks not_allowed)
				(vias allowed)
				(pads allowed)
				(copperpour not_allowed)
				(footprints allowed)
			)
			(placement
				(enabled no)
				(sheetname "")
			)
			(fill
				(thermal_gap 0.5)
				(thermal_bridge_width 0.5)
				(island_removal_mode 0)
			)
			(polygon
				(pts
					(xy 163.2966 -72.009) (xy 163.2966 -73.279) (xy 164.0586 -73.279) (xy 164.0586 -72.009)
				)
			)
		)
	)
	(footprint ""
		(layer "F.Cu")
		(at 391.16 -64.5795)
		(property "Reference" "R7E16"
			(at 0 0 0)
			(layer "F.SilkS")
			(hide yes)
			(effects
				(font
					(size 1.27 1.27)
				)
			)
		)
		(property "Value" ""
			(at 0 0 0)
			(layer "F.Fab")
			(effects
				(font
					(size 1.27 1.27)
				)
			)
		)
		(duplicate_pad_numbers_are_jumpers no)
		(fp_poly
			(pts
				(xy -0.2794 -0.1016) (xy 0.2794 -0.1016) (xy 0.2794 0.9906) (xy -0.2794 0.9906)
			)
			(stroke
				(width 0)
				(type default)
			)
			(fill no)
			(layer "F.CrtYd")
		)
		(fp_line
			(start -0.2794 -0.1016)
			(end -0.2794 0.9906)
			(stroke
				(width 0.1)
				(type default)
			)
			(layer "F.Fab")
		)
		(fp_line
			(start -0.2794 0.9906)
			(end 0.2794 0.9906)
			(stroke
				(width 0.1)
				(type default)
			)
			(layer "F.Fab")
		)
		(fp_line
			(start 0.2794 -0.1016)
			(end -0.2794 -0.1016)
			(stroke
				(width 0.1)
				(type default)
			)
			(layer "F.Fab")
		)
		(fp_line
			(start 0.2794 0.9906)
			(end 0.2794 -0.1016)
			(stroke
				(width 0.1)
				(type default)
			)
			(layer "F.Fab")
		)
		(pad "1" smd rect
			(at 0 0)
			(size 0.508 0.508)
			(layers "F.Cu" "F.Mask" "F.Paste")
			(net "VR_P5V_STBY_VSENSE")
		)
		(pad "2" smd rect
			(at 0 0.889)
			(size 0.508 0.508)
			(layers "F.Cu" "F.Mask" "F.Paste")
			(net "AGND_P5V_STBY")
		)
		(zone
			(layer "F.Cu")
			(hatch none 0.5)
			(connect_pads
				(clearance 0)
			)
			(min_thickness 0.25)
			(keepout
				(tracks allowed)
				(vias not_allowed)
				(pads allowed)
				(copperpour not_allowed)
				(footprints allowed)
			)
			(placement
				(enabled no)
				(sheetname "")
			)
			(fill
				(thermal_gap 0.5)
				(thermal_bridge_width 0.5)
				(island_removal_mode 0)
			)
			(polygon
				(pts
					(xy 390.906 -64.3255) (xy 391.414 -64.3255) (xy 391.414 -63.9445) (xy 390.906 -63.9445)
				)
			)
		)
		(zone
			(layer "F.Cu")
			(hatch none 0.5)
			(connect_pads
				(clearance 0)
			)
			(min_thickness 0.25)
			(keepout
				(tracks not_allowed)
				(vias allowed)
				(pads allowed)
				(copperpour not_allowed)
				(footprints allowed)
			)
			(placement
				(enabled no)
				(sheetname "")
			)
			(fill
				(thermal_gap 0.5)
				(thermal_bridge_width 0.5)
				(island_removal_mode 0)
			)
			(polygon
				(pts
					(xy 390.906 -63.9445) (xy 391.414 -63.9445) (xy 391.414 -64.3255) (xy 390.906 -64.3255)
				)
			)
		)
	)
	(footprint ""
		(layer "F.Cu")
		(at 191.897 -3.7465)
		(property "Reference" "C4G17"
			(at 0 0 0)
			(layer "F.SilkS")
			(hide yes)
			(effects
				(font
					(size 1.27 1.27)
				)
			)
		)
		(property "Value" ""
			(at 0 0 0)
			(layer "F.Fab")
			(effects
				(font
					(size 1.27 1.27)
				)
			)
		)
		(duplicate_pad_numbers_are_jumpers no)
		(fp_poly
			(pts
				(xy 0.3048 -0.1016) (xy 0.3048 0.9906) (xy -0.3048 0.9906) (xy -0.3048 -0.1016)
			)
			(stroke
				(width 0)
				(type default)
			)
			(fill no)
			(layer "F.CrtYd")
		)
		(fp_line
			(start -0.3048 -0.1016)
			(end -0.3048 0.9906)
			(stroke
				(width 0.1)
				(type default)
			)
			(layer "F.Fab")
		)
		(fp_line
			(start -0.3048 0.9906)
			(end 0.3048 0.9906)
			(stroke
				(width 0.1)
				(type default)
			)
			(layer "F.Fab")
		)
		(fp_line
			(start 0.3048 -0.1016)
			(end -0.3048 -0.1016)
			(stroke
				(width 0.1)
				(type default)
			)
			(layer "F.Fab")
		)
		(fp_line
			(start 0.3048 0.9906)
			(end 0.3048 -0.1016)
			(stroke
				(width 0.1)
				(type default)
			)
			(layer "F.Fab")
		)
		(pad "1" smd rect
			(at 0 0)
			(size 0.508 0.508)
			(layers "F.Cu" "F.Mask" "F.Paste")
			(net "M_C_CPU_VREF")
		)
		(pad "2" smd rect
			(at 0 0.889)
			(size 0.508 0.508)
			(layers "F.Cu" "F.Mask" "F.Paste")
			(net "GND")
		)
		(zone
			(layer "F.Cu")
			(hatch none 0.5)
			(connect_pads
				(clearance 0)
			)
			(min_thickness 0.25)
			(keepout
				(tracks allowed)
				(vias not_allowed)
				(pads allowed)
				(copperpour not_allowed)
				(footprints allowed)
			)
			(placement
				(enabled no)
				(sheetname "")
			)
			(fill
				(thermal_gap 0.5)
				(thermal_bridge_width 0.5)
				(island_removal_mode 0)
			)
			(polygon
				(pts
					(xy 191.643 -3.4925) (xy 192.151 -3.4925) (xy 192.151 -3.1115) (xy 191.643 -3.1115)
				)
			)
		)
		(zone
			(layer "F.Cu")
			(hatch none 0.5)
			(connect_pads
				(clearance 0)
			)
			(min_thickness 0.25)
			(keepout
				(tracks not_allowed)
				(vias allowed)
				(pads allowed)
				(copperpour not_allowed)
				(footprints allowed)
			)
			(placement
				(enabled no)
				(sheetname "")
			)
			(fill
				(thermal_gap 0.5)
				(thermal_bridge_width 0.5)
				(island_removal_mode 0)
			)
			(polygon
				(pts
					(xy 191.643 -3.1115) (xy 192.151 -3.1115) (xy 192.151 -3.4925) (xy 191.643 -3.4925)
				)
			)
		)
	)
	(footprint ""
		(layer "F.Cu")
		(at 440.055 -140.716 90)
		(property "Reference" "R25W177"
			(at -0.8382 -0.67818 90)
			(unlocked yes)
			(layer "F.SilkS")
			(effects
				(font
					(size 0.4064 0.254)
					(thickness 0.1524)
				)
				(justify left)
			)
		)
		(property "Value" ""
			(at 0 0 90)
			(layer "F.Fab")
			(effects
				(font
					(size 1.27 1.27)
				)
			)
		)
		(duplicate_pad_numbers_are_jumpers no)
		(fp_poly
			(pts
				(xy -0.2794 -0.1016) (xy 0.2794 -0.1016) (xy 0.2794 0.9906) (xy -0.2794 0.9906)
			)
			(stroke
				(width 0)
				(type default)
			)
			(fill no)
			(layer "F.CrtYd")
		)
		(fp_line
			(start 0.2794 -0.1016)
			(end -0.2794 -0.1016)
			(stroke
				(width 0.1)
				(type default)
			)
			(layer "F.Fab")
		)
		(fp_line
			(start -0.2794 -0.1016)
			(end -0.2794 0.9906)
			(stroke
				(width 0.1)
				(type default)
			)
			(layer "F.Fab")
		)
		(fp_line
			(start 0.2794 0.9906)
			(end 0.2794 -0.1016)
			(stroke
				(width 0.1)
				(type default)
			)
			(layer "F.Fab")
		)
		(fp_line
			(start -0.2794 0.9906)
			(end 0.2794 0.9906)
			(stroke
				(width 0.1)
				(type default)
			)
			(layer "F.Fab")
		)
		(pad "1" smd rect
			(at 0 0 90)
			(size 0.508 0.508)
			(layers "F.Cu" "F.Mask" "F.Paste")
			(net "P3V3_STBY")
		)
		(pad "2" smd rect
			(at 0 0.889 90)
			(size 0.508 0.508)
			(layers "F.Cu" "F.Mask" "F.Paste")
			(net "BMC_PREQ_BUF_N")
		)
		(zone
			(layer "F.Cu")
			(hatch none 0.5)
			(connect_pads
				(clearance 0)
			)
			(min_thickness 0.25)
			(keepout
				(tracks allowed)
				(vias not_allowed)
				(pads allowed)
				(copperpour not_allowed)
				(footprints allowed)
			)
			(placement
				(enabled no)
				(sheetname "")
			)
			(fill
				(thermal_gap 0.5)
				(thermal_bridge_width 0.5)
				(island_removal_mode 0)
			)
			(polygon
				(pts
					(xy 440.309 -140.462) (xy 440.309 -140.97) (xy 440.69 -140.97) (xy 440.69 -140.462)
				)
			)
		)
		(zone
			(layer "F.Cu")
			(hatch none 0.5)
			(connect_pads
				(clearance 0)
			)
			(min_thickness 0.25)
			(keepout
				(tracks not_allowed)
				(vias allowed)
				(pads allowed)
				(copperpour not_allowed)
				(footprints allowed)
			)
			(placement
				(enabled no)
				(sheetname "")
			)
			(fill
				(thermal_gap 0.5)
				(thermal_bridge_width 0.5)
				(island_removal_mode 0)
			)
			(polygon
				(pts
					(xy 440.69 -140.462) (xy 440.69 -140.97) (xy 440.309 -140.97) (xy 440.309 -140.462)
				)
			)
		)
	)
	(footprint ""
		(layer "F.Cu")
		(at 370.332 -136.4615 180)
		(property "Reference" "R7A14"
			(at 0 0 180)
			(layer "F.SilkS")
			(hide yes)
			(effects
				(font
					(size 1.27 1.27)
				)
			)
		)
		(property "Value" ""
			(at 0 0 180)
			(layer "F.Fab")
			(effects
				(font
					(size 1.27 1.27)
				)
			)
		)
		(duplicate_pad_numbers_are_jumpers no)
		(fp_poly
			(pts
				(xy -0.2794 -0.1016) (xy 0.2794 -0.1016) (xy 0.2794 0.9906) (xy -0.2794 0.9906)
			)
			(stroke
				(width 0)
				(type default)
			)
			(fill no)
			(layer "F.CrtYd")
		)
		(fp_line
			(start 0.2794 0.9906)
			(end 0.2794 -0.1016)
			(stroke
				(width 0.1)
				(type default)
			)
			(layer "F.Fab")
		)
		(fp_line
			(start 0.2794 -0.1016)
			(end -0.2794 -0.1016)
			(stroke
				(width 0.1)
				(type default)
			)
			(layer "F.Fab")
		)
		(fp_line
			(start -0.2794 0.9906)
			(end 0.2794 0.9906)
			(stroke
				(width 0.1)
				(type default)
			)
			(layer "F.Fab")
		)
		(fp_line
			(start -0.2794 -0.1016)
			(end -0.2794 0.9906)
			(stroke
				(width 0.1)
				(type default)
			)
			(layer "F.Fab")
		)
		(pad "1" smd rect
			(at 0 0 180)
			(size 0.508 0.508)
			(layers "F.Cu" "F.Mask" "F.Paste")
			(net "VSENSE_PVNN_PCH_STBY_FPK")
		)
		(pad "2" smd rect
			(at 0 0.889 180)
			(size 0.508 0.508)
			(layers "F.Cu" "F.Mask" "F.Paste")
			(net "VSENSE_PVNN_PCH_STBY_AVSP")
		)
		(zone
			(layer "F.Cu")
			(hatch none 0.5)
			(connect_pads
				(clearance 0)
			)
			(min_thickness 0.25)
			(keepout
				(tracks not_allowed)
				(vias allowed)
				(pads allowed)
				(copperpour not_allowed)
				(footprints allowed)
			)
			(placement
				(enabled no)
				(sheetname "")
			)
			(fill
				(thermal_gap 0.5)
				(thermal_bridge_width 0.5)
				(island_removal_mode 0)
			)
			(polygon
				(pts
					(xy 370.586 -137.0965) (xy 370.078 -137.0965) (xy 370.078 -136.7155) (xy 370.586 -136.7155)
				)
			)
		)
		(zone
			(layer "F.Cu")
			(hatch none 0.5)
			(connect_pads
				(clearance 0)
			)
			(min_thickness 0.25)
			(keepout
				(tracks allowed)
				(vias not_allowed)
				(pads allowed)
				(copperpour not_allowed)
				(footprints allowed)
			)
			(placement
				(enabled no)
				(sheetname "")
			)
			(fill
				(thermal_gap 0.5)
				(thermal_bridge_width 0.5)
				(island_removal_mode 0)
			)
			(polygon
				(pts
					(xy 370.586 -136.7155) (xy 370.078 -136.7155) (xy 370.078 -137.0965) (xy 370.586 -137.0965)
				)
			)
		)
	)
)
